# stackup discovery v1 revB.xlsx — Feuil1 (pcb-stackup)
| L1 |  | 140µm |
|  | FR4 | 2220µm |
| L2 |  | 140µm |
